# T6G (Grand Teton) — schematic netlist excerpt (pin names and nets, part order shuffled) for the footprints in the layout excerpt that follows; sources: Cadence DE-HDL packaged netlist, KiCad conversion of 04192023_DAF0TMB3IC0_F0TG_MB_C_brd_V02_OCP.brd

R148  Q_RES  0 5% EMPTY  pkg 0402LF  page 161 : A = SMB_CPU0_CPU1_SEC_SDA_R2 ; B = SMB_CPU1_SEC_R_SDA
C1074  Q_CAP  0.1UF 25V 10% X7R  pkg 0402  page 258 : A = MAX11617_2_VREF ; B = GND

(kicad_pcb
	(version 20260206)
	(generator "pcbnew")
	(generator_version "10.0")
	(general
		(thickness 1.6)
		(legacy_teardrops no)
	)
	(paper "A4")
	(title_block
		(title "04192023_DAF0TMB3IC0_F0TG_MB_C_brd_V02_OCP.brd")
		(comment 1 "Grand Teton / footprints 8056-8057 of 8354")
	)
	(layers
		(0 "F.Cu" signal "TOP")
		(4 "In1.Cu" signal "GND")
		(6 "In2.Cu" signal "IN1")
		(8 "In3.Cu" signal "GND1")
		(10 "In4.Cu" signal "IN2")
		(12 "In5.Cu" signal "GND2")
		(14 "In6.Cu" signal "IN3")
		(16 "In7.Cu" signal "GND3")
		(18 "In8.Cu" signal "VCC")
		(20 "In9.Cu" signal "VCC1")
		(22 "In10.Cu" signal "GND4")
		(24 "In11.Cu" signal "IN4")
		(26 "In12.Cu" signal "GND5")
		(28 "In13.Cu" signal "IN5")
		(30 "In14.Cu" signal "GND6")
		(32 "In15.Cu" signal "IN6")
		(34 "In16.Cu" signal "GND7")
		(2 "B.Cu" signal "BOTTOM")
		(9 "F.Adhes" user "F.Adhesive")
		(11 "B.Adhes" user "B.Adhesive")
		(13 "F.Paste" user "Package Geometry/Pastemask Top")
		(15 "B.Paste" user "Package Geometry/Pastemask Bottom")
		(5 "F.SilkS" user "Ref Des/Silkscreen Top")
		(7 "B.SilkS" user "Ref Des/Silkscreen Bottom")
		(1 "F.Mask" user "Board Geometry/Soldermask Top")
		(3 "B.Mask" user "Board Geometry/Soldermask Bottom")
		(17 "Dwgs.User" user "User.Drawings")
		(19 "Cmts.User" user "User.Comments")
		(21 "Eco1.User" user "User.Eco1")
		(23 "Eco2.User" user "User.Eco2")
		(25 "Edge.Cuts" user "Board Geometry/Outline")
		(27 "Margin" user)
		(31 "F.CrtYd" user "Package Geometry/Place Bound Top")
		(29 "B.CrtYd" user "Package Geometry/Place Bound Bottom")
		(35 "F.Fab" user "Ref Des/Assembly Top")
		(33 "B.Fab" user "Ref Des/Assembly Bottom")
	)
	(footprint ""
		(layer "B.Cu")
		(at 236.093 -234.061 -90)
		(property "Reference" "R148"
			(at 0 0 90)
			(layer "B.SilkS")
			(hide yes)
			(effects
				(font
					(size 1.27 1.27)
				)
				(justify mirror)
			)
		)
		(property "Value" ""
			(at 0 0 90)
			(layer "B.Fab")
			(effects
				(font
					(size 1.27 1.27)
				)
				(justify mirror)
			)
		)
		(duplicate_pad_numbers_are_jumpers no)
		(fp_line
			(start -0.7874 0.4064)
			(end 0.7874 0.4064)
			(stroke
				(width 0.1524)
				(type default)
			)
			(layer "B.SilkS")
		)
		(fp_line
			(start 0.7874 0.4064)
			(end 0.7874 -0.4064)
			(stroke
				(width 0.1524)
				(type default)
			)
			(layer "B.SilkS")
		)
		(fp_line
			(start -0.7874 -0.4064)
			(end -0.7874 0.4064)
			(stroke
				(width 0.1524)
				(type default)
			)
			(layer "B.SilkS")
		)
		(fp_line
			(start 0.7874 -0.4064)
			(end -0.7874 -0.4064)
			(stroke
				(width 0.1524)
				(type default)
			)
			(layer "B.SilkS")
		)
		(fp_line
			(start -0.67945 0.3048)
			(end -0.120396 0.3048)
			(stroke
				(width 0.1)
				(type default)
			)
			(layer "B.Fab")
		)
		(fp_line
			(start -0.120396 0.3048)
			(end -0.120396 0.2794)
			(stroke
				(width 0.1)
				(type default)
			)
			(layer "B.Fab")
		)
		(fp_line
			(start 0.12065 0.3048)
			(end 0.67945 0.3048)
			(stroke
				(width 0.1)
				(type default)
			)
			(layer "B.Fab")
		)
		(fp_line
			(start 0.67945 0.3048)
			(end 0.67945 -0.305054)
			(stroke
				(width 0.1)
				(type default)
			)
			(layer "B.Fab")
		)
		(fp_line
			(start -0.120396 0.2794)
			(end 0.12065 0.2794)
			(stroke
				(width 0.1)
				(type default)
			)
			(layer "B.Fab")
		)
		(fp_line
			(start 0.12065 0.2794)
			(end 0.12065 0.3048)
			(stroke
				(width 0.1)
				(type default)
			)
			(layer "B.Fab")
		)
		(fp_line
			(start -0.12065 -0.2794)
			(end -0.12065 -0.3048)
			(stroke
				(width 0.1)
				(type default)
			)
			(layer "B.Fab")
		)
		(fp_line
			(start 0.12065 -0.2794)
			(end -0.12065 -0.2794)
			(stroke
				(width 0.1)
				(type default)
			)
			(layer "B.Fab")
		)
		(fp_line
			(start -0.67945 -0.3048)
			(end -0.67945 0.3048)
			(stroke
				(width 0.1)
				(type default)
			)
			(layer "B.Fab")
		)
		(fp_line
			(start -0.12065 -0.3048)
			(end -0.67945 -0.3048)
			(stroke
				(width 0.1)
				(type default)
			)
			(layer "B.Fab")
		)
		(fp_line
			(start 0.12065 -0.305054)
			(end 0.12065 -0.2794)
			(stroke
				(width 0.1)
				(type default)
			)
			(layer "B.Fab")
		)
		(fp_line
			(start 0.67945 -0.305054)
			(end 0.12065 -0.305054)
			(stroke
				(width 0.1)
				(type default)
			)
			(layer "B.Fab")
		)
		(pad "1" smd circle
			(at 0.40005 0 90)
			(size 0 0)
			(layers "B.Cu" "B.Mask" "B.Paste")
			(net "SMB_CPU0_CPU1_SEC_SDA_R2")
		)
		(pad "2" smd circle
			(at -0.40005 0 90)
			(size 0 0)
			(layers "B.Cu" "B.Mask" "B.Paste")
			(net "SMB_CPU1_SEC_R_SDA")
		)
	)
	(footprint ""
		(layer "B.Cu")
		(at 257.232658 -327.684384 180)
		(property "Reference" "C1074"
			(at 0 0 0)
			(layer "B.SilkS")
			(hide yes)
			(effects
				(font
					(size 1.27 1.27)
				)
				(justify mirror)
			)
		)
		(property "Value" ""
			(at 0 0 0)
			(layer "B.Fab")
			(effects
				(font
					(size 1.27 1.27)
				)
				(justify mirror)
			)
		)
		(duplicate_pad_numbers_are_jumpers no)
		(fp_line
			(start 0.7874 0.4064)
			(end 0.7874 -0.4064)
			(stroke
				(width 0.1524)
				(type default)
			)
			(layer "B.SilkS")
		)
		(fp_line
			(start 0.7874 -0.4064)
			(end -0.7874 -0.4064)
			(stroke
				(width 0.1524)
				(type default)
			)
			(layer "B.SilkS")
		)
		(fp_line
			(start -0.7874 0.4064)
			(end 0.7874 0.4064)
			(stroke
				(width 0.1524)
				(type default)
			)
			(layer "B.SilkS")
		)
		(fp_line
			(start -0.7874 -0.4064)
			(end -0.7874 0.4064)
			(stroke
				(width 0.1524)
				(type default)
			)
			(layer "B.SilkS")
		)
		(fp_line
			(start 0.67945 0.3048)
			(end 0.67945 -0.305054)
			(stroke
				(width 0.1)
				(type default)
			)
			(layer "B.Fab")
		)
		(fp_line
			(start 0.67945 -0.305054)
			(end 0.12065 -0.305054)
			(stroke
				(width 0.1)
				(type default)
			)
			(layer "B.Fab")
		)
		(fp_line
			(start 0.12065 0.3048)
			(end 0.67945 0.3048)
			(stroke
				(width 0.1)
				(type default)
			)
			(layer "B.Fab")
		)
		(fp_line
			(start 0.12065 0.2794)
			(end 0.12065 0.3048)
			(stroke
				(width 0.1)
				(type default)
			)
			(layer "B.Fab")
		)
		(fp_line
			(start 0.12065 -0.2794)
			(end -0.12065 -0.2794)
			(stroke
				(width 0.1)
				(type default)
			)
			(layer "B.Fab")
		)
		(fp_line
			(start 0.12065 -0.305054)
			(end 0.12065 -0.2794)
			(stroke
				(width 0.1)
				(type default)
			)
			(layer "B.Fab")
		)
		(fp_line
			(start -0.120396 0.3048)
			(end -0.120396 0.2794)
			(stroke
				(width 0.1)
				(type default)
			)
			(layer "B.Fab")
		)
		(fp_line
			(start -0.120396 0.2794)
			(end 0.12065 0.2794)
			(stroke
				(width 0.1)
				(type default)
			)
			(layer "B.Fab")
		)
		(fp_line
			(start -0.12065 -0.2794)
			(end -0.12065 -0.3048)
			(stroke
				(width 0.1)
				(type default)
			)
			(layer "B.Fab")
		)
		(fp_line
			(start -0.12065 -0.3048)
			(end -0.67945 -0.3048)
			(stroke
				(width 0.1)
				(type default)
			)
			(layer "B.Fab")
		)
		(fp_line
			(start -0.67945 0.3048)
			(end -0.120396 0.3048)
			(stroke
				(width 0.1)
				(type default)
			)
			(layer "B.Fab")
		)
		(fp_line
			(start -0.67945 -0.3048)
			(end -0.67945 0.3048)
			(stroke
				(width 0.1)
				(type default)
			)
			(layer "B.Fab")
		)
		(pad "1" smd circle
			(at 0.40005 0)
			(size 0 0)
			(layers "B.Cu" "B.Mask" "B.Paste")
			(net "MAX11617_2_VREF")
		)
		(pad "2" smd circle
			(at -0.40005 0)
			(size 0 0)
			(layers "B.Cu" "B.Mask" "B.Paste")
			(net "GND")
		)
	)
)
